FILE_TYPE = CONNECTIVITY;
{Allegro Design Entry HDL 17.4-2019 S026 (4007227) 1/17/2022}
"PAGE_NUMBER" = 180;
0"NC";
1"GND\g";
2"GND\g";
3"GND\g";
4"GND\g";
5"GND\g";
6"GND\g";
7"GND\g";
8"GND\g";
9"GND\g";
10"GND\g";
11"GND\g";
12"PVDDIO_P0_TEMP1";
13"PVDDIO_P0_PWM2";
14"NC_PVDDIO_P0_DNC2";
15"PVDDCR_CPU1_P0_VCCS"CDS_PHYS_NET_NAME"PVDDCR_CPU1_P0_VCCS";
16"PVDDIO_P0_IMON2";
17"SW_P12V_AUX_PVDDIO_P0_FLT\g";
18"GND\g";
19"PVDDIO_P0\g";
20"GND\g";
21"P12V_AUX\g";
22"GND\g";
23"PVDDIO_P0\g";
24"GND\g";
25"PVDDIO_P0\g";
26"GND\g";
27"SW_P12V_AUX_PVDDIO_P0_FLT\g";
28"GND\g";
29"GND\g";
30"PVDDCR_CPU1_P0_PVCC\g";
31"GND\g";
32"PVDDCR_CPU1_P0_PVCC\g";
33"PVDDIO_P0_VOS1";
34"SW_PVDDIO_P0_SW1";
35"SW_PVDDIO_P0_BOOTR1";
36"SW_PVDDIO_P0_BOOT1";
37"PVDDIO_P0_LSET1"CDS_PHYS_NET_NAME"PVDDIO_P0_LSET1";
38"PVDDIO_P0_TEMP1";
39"PVDDIO_P0_PWM1";
40"SW_PVDDIO_P0_BOOT1_R";
41"SW_PVDDIO_P0_BOOT2";
42"SW_PVDDIO_P0_BOOT2_R";
43"PVDDIO_P0_LSET2";
44"NC_PVDDIO_P0_GL2_2";
45"NC_PVDDIO_P0_GL1_2";
46"PVDDIO_P0_VOS2";
47"PVDDIO_P0_VCC2"CDS_PHYS_NET_NAME"PVDDIO_P0_VCC2";
48"PVDDCR_CPU1_P0_VCCS"CDS_PHYS_NET_NAME"PVDDCR_CPU1_P0_VCCS";
49"PVDDIO_P0_IMON1";
50"NC_PVDDIO_P0_DNC1";
51"PVDDIO_P0_VCC1"CDS_PHYS_NET_NAME"PVDDIO_P0_VCC1";
52"NC_PVDDIO_P0_GL2_1";
53"NC_PVDDIO_P0_GL1_1";
54"SW_PVDDIO_P0_BOOTR2";
55"SW_PVDDIO_P0_SW2";
56"SW_PVDDIO_P0_SW2_RC";
57"IND_PVDDIO_P0_CPL3";
58"IND_PVDDIO_P0_CPL2";
59"SW_PVDDIO_P0_SW1_RC";
60"IND_PVDDIO_P0_CPL2";
%"UNIVERSAL_GND"
"1","(275,1600)","0","pure_quanta_power","I1";
;
CDS_LIB"pure_quanta_power"
HDL_POWER"GND";
"A"1;
%"Q_CAP"
"1","(1175,2575)","0","pure_quanta","I10";
;
LOCATION"PC142"
$SEC"1"
CDS_SEC"1"
PACK_TYPE"C0402"
VOLTAGE"10V"
VALUE"2.2UF"
TOLERANCE"10%"
MATERIAL"X6S"
CDS_LIB"pure_quanta"
PART_NUMBER"CH5222KEB01";
"B"
$PN"2"11;
"A"
$PN"1"47;
%"UNIVERSAL_GND"
"1","(1525,2875)","0","pure_quanta_power","I11";
;
CDS_LIB"pure_quanta_power"
HDL_POWER"GND";
"A"2;
%"Q_RES"
"2","(1175,3125)","0","pure_quanta","I12";
;
LOCATION"PR99"
$SEC"1"
CDS_SEC"1"
WATTAGE"1/16W"
MATERIAL"CHIP"
TOLERANCE"1%"
PACK_TYPE"0402LF"
VALUE"2.2"
CDS_LIB"pure_quanta"
PART_NUMBER"CS-2202FB01";
"A"
$PN"1"32;
"B"
$PN"2"47;
%"Q_CAP"
"1","(1525,3150)","0","pure_quanta","I13";
;
LOCATION"PC144_IOP0_2"
$SEC"1"
CDS_SEC"1"
VALUE"2.2UF"
PACK_TYPE"C0402"
TOLERANCE"10%"
MATERIAL"X6S"
VOLTAGE"10V"
CDS_LIB"pure_quanta"
PART_NUMBER"CH5222KEB01";
"B"
$PN"2"2;
"A"
$PN"1"32;
%"VCC_CORE"
"1","(1175,3550)","0","pure_quanta_power","I14";
;
HDL_POWER"PVDDCR_CPU1_P0_PVCC"
CDS_LIB"pure_quanta_power";
"A"32;
%"ISL99390FRZTR5935"
"1","(2850,2175)","0","pure_quanta","I15";
;
LOCATION"PU18"
$SEC"1"
CDS_SEC"1"
VALUE"ISL99390FRZ-TR5935"
PART_TYPE"SMLF"
MATERIAL"IC"
CDS_LMAN_SYM_OUTLINE"-300,700,250,-650"
NEEDS_NO_SIZE"TRUE"
CDS_LIB"pure_quanta"
PART_NUMBER"AL099390004";
"PGND2"
$PN"7_9-20_24"31;
"GL2"
$PN"41"44;
"GL1"
$PN"6"45;
"DNC"
$PN"31"14;
"EN"
$PN"35"47;
"PGND3"
$PN"40"31;
"VOS"
$PN"1"46;
"VIN2"
$PN"30"27;
"PGND1"
$PN"5"31;
"SW"
$PN"10_19"55;
"LSET"
$PN"37"43;
"IOUT"
$PN"38"16;
"TOUT_FLT"
$PN"36"12;
"PVCC"
$PN"4"32;
"PHASE"
$PN"32"54;
"VIN1"
$PN"25_29"27;
"BOOT"
$PN"33"41;
"AGND"
$PN"2"31;
"VCC"
$PN"3"47;
"REFIN"
$PN"39"15;
"PWM"
$PN"34"13;
%"UNIVERSAL_GND"
"1","(3500,1450)","0","pure_quanta_power","I16";
;
CDS_LIB"pure_quanta_power"
HDL_POWER"GND";
"A"31;
%"Q_RES"
"1","(4125,2525)","0","pure_quanta","I17";
;
LOCATION"PR102"
$SEC"1"
CDS_SEC"1"
VALUE"5.6"
PACK_TYPE"0402LF"
WATTAGE"1/16W"
MATERIAL"CHIP"
TOLERANCE"1%"
CDS_LIB"pure_quanta"
PART_NUMBER"CS-5602FB01";
"B"
$PN"2"42;
"A"
$PN"1"41;
%"Q_CAP"
"1","(3675,3100)","0","pure_quanta","I18";
;
LOCATION"PC149_2"
$SEC"1"
CDS_SEC"1"
VALUE"0.1UF"
PACK_TYPE"0402"
VOLTAGE"25V"
MATERIAL"X7R"
TOLERANCE"10%"
CDS_LIB"pure_quanta"
PART_NUMBER"CH4104K1B00";
"B"
$PN"2"28;
"A"
$PN"1"27;
%"UNIVERSAL_GND"
"1","(250,4350)","0","pure_quanta_power","I19";
;
CDS_LIB"pure_quanta_power"
HDL_POWER"GND";
"A"3;
%"Q_CAP"
"1","(275,1800)","0","pure_quanta","I2";
;
LOCATION"PC146_8"
$SEC"1"
CDS_SEC"1"
TOLERANCE"10%"
MATERIAL"X7R"
PACK_TYPE"0402"
VALUE"0.1UF"
VOLTAGE"25V"
CDS_LIB"pure_quanta"
PART_NUMBER"CH4104K1B00";
"B"
$PN"2"1;
"A"
$PN"1"15;
%"Q_CAP"
"1","(250,4600)","0","pure_quanta","I20";
;
LOCATION"PC145_7"
$SEC"1"
CDS_SEC"1"
MATERIAL"X7R"
PACK_TYPE"0402"
VOLTAGE"25V"
VALUE"0.1UF"
TOLERANCE"10%"
CDS_LIB"pure_quanta"
PART_NUMBER"CH4104K1B00";
"B"
$PN"2"3;
"A"
$PN"1"48;
%"UNIVERSAL_GND"
"1","(875,4300)","0","pure_quanta_power","I21";
;
CDS_LIB"pure_quanta_power"
HDL_POWER"GND";
"A"4;
%"Q_RES"
"2","(875,4525)","2","pure_quanta","I22";
;
LOCATION"PR98"
$SEC"1"
CDS_SEC"1"
MATERIAL"EMPTY"
VALUE"8.87K"
PACK_TYPE"0402LF"
WATTAGE"1/16W"
TOLERANCE"1%"
CDS_LIB"pure_quanta"
PART_NUMBER"CS28872FB01";
"A"
$PN"1"37;
"B"
$PN"2"4;
%"UNIVERSAL_GND"
"1","(1275,5050)","0","pure_quanta_power","I27";
;
CDS_LIB"pure_quanta_power"
HDL_POWER"GND";
"A"5;
%"Q_CAP"
"1","(1275,5250)","0","pure_quanta","I28";
;
LOCATION"PC143"
$SEC"1"
CDS_SEC"1"
PACK_TYPE"C0402"
VOLTAGE"10V"
VALUE"2.2UF"
TOLERANCE"10%"
MATERIAL"X6S"
CDS_LIB"pure_quanta"
PART_NUMBER"CH5222KEB01";
"B"
$PN"2"5;
"A"
$PN"1"51;
%"Q_RES"
"2","(1275,5800)","0","pure_quanta","I29";
;
LOCATION"PR100"
$SEC"1"
CDS_SEC"1"
WATTAGE"1/16W"
MATERIAL"CHIP"
TOLERANCE"1%"
VALUE"2.2"
PACK_TYPE"0402LF"
CDS_LIB"pure_quanta"
PART_NUMBER"CS-2202FB01";
"A"
$PN"1"30;
"B"
$PN"2"51;
%"UNIVERSAL_GND"
"1","(850,1450)","0","pure_quanta_power","I3";
;
CDS_LIB"pure_quanta_power"
HDL_POWER"GND";
"A"6;
%"UNIVERSAL_GND"
"1","(1625,5550)","0","pure_quanta_power","I30";
;
CDS_LIB"pure_quanta_power"
HDL_POWER"GND";
"A"7;
%"Q_CAP"
"1","(1625,5825)","0","pure_quanta","I31";
;
LOCATION"PC147_IOP0_1"
$SEC"1"
CDS_SEC"1"
TOLERANCE"10%"
PACK_TYPE"C0402"
VOLTAGE"10V"
VALUE"2.2UF"
MATERIAL"X6S"
CDS_LIB"pure_quanta"
PART_NUMBER"CH5222KEB01";
"B"
$PN"2"7;
"A"
$PN"1"30;
%"VCC_CORE"
"1","(1275,6225)","0","pure_quanta_power","I32";
;
HDL_POWER"PVDDCR_CPU1_P0_PVCC"
CDS_LIB"pure_quanta_power";
"A"30;
%"UNIVERSAL_GND"
"1","(3500,4250)","0","pure_quanta_power","I33";
;
CDS_LIB"pure_quanta_power"
HDL_POWER"GND";
"A"29;
%"Q_RES"
"1","(3950,5325)","0","pure_quanta","I34";
;
LOCATION"PR101"
$SEC"1"
CDS_SEC"1"
VALUE"5.6"
PACK_TYPE"0402LF"
TOLERANCE"1%"
MATERIAL"CHIP"
WATTAGE"1/16W"
CDS_LIB"pure_quanta"
PART_NUMBER"CS-5602FB01";
"B"
$PN"2"40;
"A"
$PN"1"36;
%"UNIVERSAL_GND"
"1","(4325,1250)","0","pure_quanta_power","I35";
;
CDS_LIB"pure_quanta_power"
HDL_POWER"GND";
"A"8;
%"Q_RES"
"2","(4325,1475)","0","pure_quanta","I36";
;
LOCATION"PR223"
$SEC"1"
CDS_SEC"1"
MATERIAL"EMPTY"
WATTAGE"1/8W"
TOLERANCE"1%"
PACK_TYPE"0402LF"
VALUE"1.5"
CDS_LIB"pure_quanta"
PART_NUMBER"CS-1504FB00";
"A"
$PN"1"56;
"B"
$PN"2"8;
%"Q_CAP"
"1","(4325,1975)","0","pure_quanta","I37";
;
LOCATION"PC159"
$SEC"1"
CDS_SEC"1"
PACK_TYPE"C0402"
VOLTAGE"50V"
VALUE"560PF"
TOLERANCE"10%"
MATERIAL"EMPTY"
CDS_LIB"pure_quanta"
PART_NUMBER"CH1566K1B09";
"B"
$PN"2"56;
"A"
$PN"1"55;
%"Q_RES"
"1","(5450,1150)","0","pure_quanta","I39";
;
LOCATION"PR104"
$SEC"1"
CDS_SEC"1"
WATTAGE"1/16W"
MATERIAL"CHIP"
TOLERANCE"5%"
VALUE"0"
PACK_TYPE"0402LF"
CDS_LIB"pure_quanta"
PART_NUMBER"CS00002JB13";
"B"
$PN"2"25;
"A"
$PN"1"46;
%"Q_RES"
"2","(850,1675)","2","pure_quanta","I4";
;
LOCATION"PR97"
$SEC"1"
CDS_SEC"1"
PACK_TYPE"0402LF"
WATTAGE"1/16W"
MATERIAL"EMPTY"
TOLERANCE"1%"
VALUE"8.87K"
CDS_LIB"pure_quanta"
PART_NUMBER"CS28872FB01";
"A"
$PN"1"43;
"B"
$PN"2"6;
%"Q_INDUCTOR4P_14"
"1","(6225,2050)","0","pure_quanta","I40";
;
LOCATION"PL18"
$SEC"1"
CDS_SEC"1"
VALUE"150NH"
MATERIAL"IND"
PART_TYPE"SMLF"
NEEDS_NO_SIZE"TRUE"
CDS_LIB"pure_quanta"
PART_NUMBER"CV+15^0TZ04";
"1"
$PN"1"55;
"4"
$PN"4"25;
"3"
$PN"3"58;
"2"
$PN"2"57;
%"Q_CAP"
"1","(4850,2400)","0","pure_quanta","I41";
;
LOCATION"PC156"
$SEC"1"
CDS_SEC"1"
VOLTAGE"16V"
VALUE"0.22UF"
TOLERANCE"10%"
MATERIAL"X7R"
PACK_TYPE"0402"
CDS_LIB"pure_quanta"
PART_NUMBER"CH4223K1B00";
"B"
$PN"2"54;
"A"
$PN"1"42;
%"Q_CAP"
"1","(4175,3100)","0","pure_quanta","I42";
;
LOCATION"PC151_2"
$SEC"1"
CDS_SEC"1"
PACK_TYPE"C0402"
VOLTAGE"25V"
VALUE"1UF"
TOLERANCE"10%"
MATERIAL"X6S"
CDS_LIB"pure_quanta"
PART_NUMBER"CH5104KEB02";
"B"
$PN"2"28;
"A"
$PN"1"27;
%"Q_CAP"
"1","(4575,3100)","0","pure_quanta","I43";
;
LOCATION"PC153_2"
$SEC"1"
CDS_SEC"1"
PACK_TYPE"C0805"
MATERIAL"X6S"
TOLERANCE"20%"
VOLTAGE"16V"
VALUE"22UF"
CDS_LIB"pure_quanta"
PART_NUMBER"CH6223MEA01";
"B"
$PN"2"28;
"A"
$PN"1"27;
%"UNIVERSAL_GND"
"1","(4325,4000)","0","pure_quanta_power","I44";
;
CDS_LIB"pure_quanta_power"
HDL_POWER"GND";
"A"9;
%"Q_CAP"
"1","(4975,3100)","0","pure_quanta","I45";
;
LOCATION"PC157_2"
$SEC"1"
CDS_SEC"1"
TOLERANCE"20%"
VOLTAGE"16V"
VALUE"22UF"
MATERIAL"X6S"
PACK_TYPE"C0805"
CDS_LIB"pure_quanta"
PART_NUMBER"CH6223MEA01";
"B"
$PN"2"28;
"A"
$PN"1"27;
%"UNIVERSAL_GND"
"1","(5450,2750)","0","pure_quanta_power","I46";
;
CDS_LIB"pure_quanta_power"
HDL_POWER"GND";
"A"28;
%"Q_CAP"
"1","(5450,3100)","0","pure_quanta","I47";
;
LOCATION"PC159_2"
$SEC"1"
CDS_SEC"1"
TOLERANCE"20%"
VOLTAGE"16V"
VALUE"22UF"
MATERIAL"X6S"
PACK_TYPE"C0805"
CDS_LIB"pure_quanta"
PART_NUMBER"CH6223MEA01";
"B"
$PN"2"28;
"A"
$PN"1"27;
%"VCC_CORE"
"1","(5450,3475)","0","pure_quanta_power","I48";
;
HDL_POWER"SW_P12V_AUX_PVDDIO_P0_FLT"
CDS_LIB"pure_quanta_power";
"A"27;
%"Q_RES"
"1","(5450,3875)","0","pure_quanta","I49";
;
LOCATION"PR103"
$SEC"1"
CDS_SEC"1"
PACK_TYPE"0402LF"
MATERIAL"CHIP"
TOLERANCE"5%"
VALUE"0"
WATTAGE"1/16W"
CDS_LIB"pure_quanta"
PART_NUMBER"CS00002JB13";
"B"
$PN"2"19;
"A"
$PN"1"33;
%"Q_CAP"
"1","(7650,1975)","0","pure_quanta","I51";
;
LOCATION"PC168_2"
$SEC"1"
CDS_SEC"1"
PACK_TYPE"C0805"
MATERIAL"X6S"
TOLERANCE"20%"
VALUE"22UF"
VOLTAGE"4V"
CDS_LIB"pure_quanta"
PART_NUMBER"CH622KMEA03";
"B"
$PN"2"26;
"A"
$PN"1"25;
%"UNIVERSAL_GND"
"1","(8075,1625)","0","pure_quanta_power","I52";
;
CDS_LIB"pure_quanta_power"
HDL_POWER"GND";
"A"26;
%"Q_CAP"
"1","(8075,1975)","0","pure_quanta","I53";
;
LOCATION"PC170_2"
$SEC"1"
CDS_SEC"1"
PACK_TYPE"C0805"
MATERIAL"X6S"
TOLERANCE"20%"
VALUE"22UF"
VOLTAGE"4V"
CDS_LIB"pure_quanta"
PART_NUMBER"CH622KMEA03";
"B"
$PN"2"26;
"A"
$PN"1"25;
%"Q_CAPP"
"1","(7150,3175)","0","pure_quanta","I54";
;
LOCATION"PC160"
$SEC"1"
CDS_SEC"1"
VOLTAGE"2.5V"
VALUE"470UF"
TOLERANCE"20%"
MATERIAL"EMPTY"
PACK_TYPE"SMLF"
CDS_LIB"pure_quanta"
PART_NUMBER"CH747LM8825";
"A"
$PN"1"23;
"B"
$PN"2"24;
%"VCC_CORE"
"1","(8075,2325)","0","pure_quanta_power","I55";
;
HDL_POWER"PVDDIO_P0"
CDS_LIB"pure_quanta_power";
"A"25;
%"UNIVERSAL_GND"
"1","(7950,2825)","0","pure_quanta_power","I56";
;
CDS_LIB"pure_quanta_power"
HDL_POWER"GND";
"A"24;
%"Q_CAPP"
"1","(7550,3175)","0","pure_quanta","I57";
;
LOCATION"PC162"
$SEC"1"
CDS_SEC"1"
MATERIAL"SPCAP"
TOLERANCE"20%"
VALUE"470UF"
VOLTAGE"2.5V"
PACK_TYPE"SMLF"
CDS_LIB"pure_quanta"
PART_NUMBER"CH747LM8825";
"A"
$PN"1"23;
"B"
$PN"2"24;
%"Q_CAPP"
"1","(7950,3175)","0","pure_quanta","I58";
;
LOCATION"PC165"
$SEC"1"
CDS_SEC"1"
PACK_TYPE"SMLF"
VOLTAGE"2.5V"
VALUE"470UF"
TOLERANCE"20%"
MATERIAL"SPCAP"
CDS_LIB"pure_quanta"
PART_NUMBER"CH747LM8825";
"A"
$PN"1"23;
"B"
$PN"2"24;
%"VCC_CORE"
"1","(7950,3500)","0","pure_quanta_power","I59";
;
HDL_POWER"PVDDIO_P0"
CDS_LIB"pure_quanta_power";
"A"23;
%"Q_RES"
"2","(4325,4225)","0","pure_quanta","I60";
;
LOCATION"PR221"
$SEC"1"
CDS_SEC"1"
PACK_TYPE"0402LF"
VALUE"1.5"
MATERIAL"EMPTY"
WATTAGE"1/8W"
TOLERANCE"1%"
CDS_LIB"pure_quanta"
PART_NUMBER"CS-1504FB00";
"A"
$PN"1"59;
"B"
$PN"2"9;
%"Q_CAP"
"1","(4325,4775)","0","pure_quanta","I61";
;
LOCATION"PC158"
$SEC"1"
CDS_SEC"1"
PACK_TYPE"C0402"
TOLERANCE"10%"
MATERIAL"EMPTY"
VOLTAGE"50V"
VALUE"560PF"
CDS_LIB"pure_quanta"
PART_NUMBER"CH1566K1B09";
"B"
$PN"2"59;
"A"
$PN"1"34;
%"Q_CAP"
"1","(4850,5200)","0","pure_quanta","I63";
;
LOCATION"PC155"
$SEC"1"
CDS_SEC"1"
VALUE"0.22UF"
PACK_TYPE"0402"
VOLTAGE"16V"
MATERIAL"X7R"
TOLERANCE"10%"
CDS_LIB"pure_quanta"
PART_NUMBER"CH4223K1B00";
"B"
$PN"2"35;
"A"
$PN"1"40;
%"Q_INDUCTOR4P_14"
"1","(6050,4850)","0","pure_quanta","I64";
;
LOCATION"PL17"
$SEC"1"
CDS_SEC"1"
VALUE"150NH"
MATERIAL"IND"
PART_TYPE"SMLF"
CDS_LIB"pure_quanta"
NEEDS_NO_SIZE"TRUE"
PART_NUMBER"CV+15^0TZ04";
"1"
$PN"1"34;
"4"
$PN"4"19;
"3"
$PN"3"22;
"2"
$PN"2"60;
%"UNIVERSAL_GND"
"1","(5450,5525)","0","pure_quanta_power","I65";
;
CDS_LIB"pure_quanta_power"
HDL_POWER"GND";
"A"18;
%"Q_CAP"
"1","(5075,5900)","0","pure_quanta","I66";
;
LOCATION"PC158_1"
$SEC"1"
CDS_SEC"1"
PACK_TYPE"C0805"
VALUE"22UF"
MATERIAL"X6S"
TOLERANCE"20%"
VOLTAGE"16V"
CDS_LIB"pure_quanta"
PART_NUMBER"CH6223MEA01";
"B"
$PN"2"18;
"A"
$PN"1"17;
%"Q_CAPP"
"1","(5725,5900)","0","pure_quanta","I67";
;
LOCATION"PC164"
$SEC"1"
CDS_SEC"1"
TOLERANCE"20%"
PACK_TYPE"THLF"
MATERIAL"OSCON"
VOLTAGE"16V"
VALUE"270UF"
CDS_LIB"pure_quanta"
PART_NUMBER"CC72703MD38";
"A"
$PN"1"17;
"B"
$PN"2"18;
%"VCC_CORE"
"1","(5450,6250)","0","pure_quanta_power","I68";
;
HDL_POWER"SW_P12V_AUX_PVDDIO_P0_FLT"
CDS_LIB"pure_quanta_power";
"A"17;
%"Q_INDUCTOR"
"1","(6075,6150)","0","pure_quanta","I69";
;
LOCATION"PL19"
$SEC"1"
CDS_SEC"1"
MATERIAL"IND"
PACK_TYPE"SMLF"
VALUE"50NH/86A"
CDS_LIB"pure_quanta"
NEEDS_NO_SIZE"TRUE"
PART_NUMBER"CVA50^0MZ09";
"1"
$PN"1"17;
"2"
$PN"2"21;
%"UNIVERSAL_GND"
"1","(6925,4600)","0","pure_quanta_power","I70";
;
CDS_LIB"pure_quanta_power"
HDL_POWER"GND";
"A"22;
%"UNIVERSAL_GND"
"1","(6600,5600)","0","pure_quanta_power","I71";
;
CDS_LIB"pure_quanta_power"
HDL_POWER"GND";
"A"10;
%"Q_CAP"
"1","(6600,5925)","0","pure_quanta","I72";
;
LOCATION"PC148"
$SEC"1"
CDS_SEC"1"
TOLERANCE"10%"
PACK_TYPE"0402"
VOLTAGE"25V"
MATERIAL"X7R"
VALUE"0.1UF"
CDS_LIB"pure_quanta"
PART_NUMBER"CH4104K1B00";
"B"
$PN"2"10;
"A"
$PN"1"21;
%"Q_CAP"
"1","(7200,4775)","0","pure_quanta","I73";
;
LOCATION"PC107"
$SEC"1"
CDS_SEC"1"
VALUE"0.1UF"
PACK_TYPE"0402"
VOLTAGE"25V"
TOLERANCE"10%"
MATERIAL"X7R"
CDS_LIB"pure_quanta"
PART_NUMBER"CH4104K1B00";
"B"
$PN"2"20;
"A"
$PN"1"19;
%"Q_CAP"
"1","(7700,4775)","0","pure_quanta","I74";
;
LOCATION"PC166_1"
$SEC"1"
CDS_SEC"1"
PACK_TYPE"C0805"
MATERIAL"X6S"
TOLERANCE"20%"
VALUE"22UF"
VOLTAGE"4V"
CDS_LIB"pure_quanta"
PART_NUMBER"CH622KMEA03";
"B"
$PN"2"20;
"A"
$PN"1"19;
%"Q_CAP"
"1","(8125,4775)","0","pure_quanta","I75";
;
LOCATION"PC169_1"
$SEC"1"
CDS_SEC"1"
PACK_TYPE"C0805"
MATERIAL"X6S"
TOLERANCE"20%"
VALUE"22UF"
VOLTAGE"4V"
CDS_LIB"pure_quanta"
PART_NUMBER"CH622KMEA03";
"B"
$PN"2"20;
"A"
$PN"1"19;
%"VCC_CORE"
"1","(6600,6250)","0","pure_quanta_power","I76";
;
HDL_POWER"P12V_AUX"
CDS_LIB"pure_quanta_power";
"A"21;
%"UNIVERSAL_GND"
"1","(8425,4425)","0","pure_quanta_power","I77";
;
CDS_LIB"pure_quanta_power"
HDL_POWER"GND";
"A"20;
%"Q_RES"
"2","(8425,4775)","0","pure_quanta","I78";
;
LOCATION"PR410"
$SEC"1"
CDS_SEC"1"
WATTAGE"1/16W"
MATERIAL"CHIP"
TOLERANCE"1%"
VALUE"1K"
PACK_TYPE"0402LF"
CDS_LIB"pure_quanta"
PART_NUMBER"CS21002FB06";
"A"
$PN"1"19;
"B"
$PN"2"20;
%"VCC_CORE"
"1","(8425,5100)","0","pure_quanta_power","I79";
;
HDL_POWER"PVDDIO_P0"
CDS_LIB"pure_quanta_power";
"A"19;
%"Q_CAP"
"1","(4750,5875)","0","pure_quanta","I80";
;
LOCATION"PC154_1"
$SEC"1"
CDS_SEC"1"
PACK_TYPE"C0805"
VALUE"22UF"
MATERIAL"X6S"
TOLERANCE"20%"
VOLTAGE"16V"
CDS_LIB"pure_quanta"
PART_NUMBER"CH6223MEA01";
"B"
$PN"2"18;
"A"
$PN"1"17;
%"Q_CAP"
"1","(4425,5875)","0","pure_quanta","I81";
;
LOCATION"PC152_1"
$SEC"1"
CDS_SEC"1"
VALUE"22UF"
VOLTAGE"16V"
MATERIAL"X6S"
PACK_TYPE"C0805"
TOLERANCE"20%"
CDS_LIB"pure_quanta"
PART_NUMBER"CH6223MEA01";
"B"
$PN"2"18;
"A"
$PN"1"17;
%"Q_CAP"
"1","(4025,5875)","0","pure_quanta","I82";
;
LOCATION"PC150_1"
$SEC"1"
CDS_SEC"1"
VOLTAGE"25V"
VALUE"1UF"
TOLERANCE"10%"
MATERIAL"X6S"
PACK_TYPE"C0402"
CDS_LIB"pure_quanta"
PART_NUMBER"CH5104KEB02";
"B"
$PN"2"18;
"A"
$PN"1"17;
%"Q_CAP"
"1","(3600,5875)","0","pure_quanta","I83";
;
LOCATION"PC148_1"
$SEC"1"
CDS_SEC"1"
MATERIAL"X7R"
TOLERANCE"10%"
VALUE"0.1UF"
VOLTAGE"25V"
PACK_TYPE"0402"
CDS_LIB"pure_quanta"
PART_NUMBER"CH4104K1B00";
"B"
$PN"2"18;
"A"
$PN"1"17;
%"ISL99390FRZTR5935"
"1","(2850,4975)","0","pure_quanta","I84";
;
LOCATION"PU17"
$SEC"1"
CDS_SEC"1"
VALUE"ISL99390FRZ-TR5935"
MATERIAL"IC"
PART_TYPE"SMLF"
CDS_LMAN_SYM_OUTLINE"-300,700,250,-650"
NEEDS_NO_SIZE"TRUE"
CDS_LIB"pure_quanta"
PART_NUMBER"AL099390004";
"PGND2"
$PN"7_9-20_24"29;
"GL2"
$PN"41"52;
"GL1"
$PN"6"53;
"DNC"
$PN"31"50;
"EN"
$PN"35"51;
"PGND3"
$PN"40"29;
"VOS"
$PN"1"33;
"VIN2"
$PN"30"17;
"PGND1"
$PN"5"29;
"SW"
$PN"10_19"34;
"LSET"
$PN"37"37;
"IOUT"
$PN"38"49;
"TOUT_FLT"
$PN"36"38;
"PVCC"
$PN"4"30;
"PHASE"
$PN"32"35;
"VIN1"
$PN"25_29"17;
"BOOT"
$PN"33"36;
"AGND"
$PN"2"29;
"VCC"
$PN"3"51;
"REFIN"
$PN"39"48;
"PWM"
$PN"34"39;
%"Q_CAP"
"1","(5425,5900)","0","pure_quanta","I85";
;
LOCATION"PC7000"
$SEC"1"
CDS_SEC"1"
PACK_TYPE"C0805"
MATERIAL"X6S"
TOLERANCE"20%"
VOLTAGE"16V"
VALUE"22UF"
CDS_LIB"pure_quanta"
PART_NUMBER"CH6223MEA01";
"B"
$PN"2"18;
"A"
$PN"1"17;
%"UNIVERSAL_GND"
"1","(1175,2375)","0","pure_quanta_power","I9";
;
CDS_LIB"pure_quanta_power"
HDL_POWER"GND";
"A"11;
END.
